FILE_TYPE = CONNECTIVITY;
{Allegro Design Entry HDL 16.6-p007 (v16-6-112F) 10/10/2012}
"PAGE_NUMBER" = 191;
0"NC";
1"P3V3_STBY\g";
2"P3V3_STBY\g";
3"FM_ADR_SMI_GPIO_R_N";
4"PU_FAB2_MARKER_CPLD";
5"PWRGD_P3V3_STBY";
6"FM_CPU1_THERMTRIP_LVT3_N";
7"FM_CPLD_ADR_TRIGGER_N";
8"PWRGD_PCH_PWROK";
9"RST_BMC_SYSRST_BTN_OUT_B_N";
10"PWRGD_CPUPWRGD";
11"FM_PVPP_CPU1_EN";
12"FM_CPU0_THERMTRIP_LVT3_N";
13"FM_PVDDQ_DEF_EN";
14"FM_PVDDQ_KLM_EN";
15"FM_PVDDQ_ABC_EN";
16"FM_FAST_PROCHOT_THROTTLE_IN_N";
17"FM_FAST_PROCHOT_THROTTLE_DLY_N";
18"FM_WBG_PRSNT_N";
19"FM_UV_ADR_TRIGGER_N";
20"FM_UV_ADR_TRIGGER_EN";
21"FM_CPU0_THERMTRIP_LATCH_LVT3_N";
22"FM_MEM_THERM_EVENT_PCH_N";
23"FM_PVDDQ_GHJ_EN";
24"PWRGD_PVCCIO_CPU1";
25"FM_PVCCIN_PVCCSA_CPU1_EN_LVC1";
26"PWRGD_P1V8MCP_CPU1";
27"PWRGD_P1V8MCP_CPU0";
28"FM_P1V8MCP_CPU0_EN";
29"FM_P1V8MCP_CPU1_EN";
30"FM_CPU0_MCP_CLK_EN_N";
31"FM_CPU1_MCP_CLK_EN_N";
32"FM_CPU1_VRM_OSC_EN";
33"FM_CPU1_FIVR_FAULT_LVT3";
34"FM_PVPP_CPU0_EN";
35"FM_P12V_MAIN_SW_EN";
36"FM_CPU1_PROC_ID1";
37"FM_CPU0_FIVR_FAULT_LVT3";
38"RST_PLTRST_BUF_N";
39"FM_THERMTRIP_DLY";
40"FM_MEM_THERM_EVENT_LVT3_N";
41"FM_CPU1_PROC_ID0";
42"TP_CPLD1_PR12D";
43"TP_CPLD1_PR11B";
44"TP_CPLD1_PR10C";
45"TP_CPLD1_PR9D";
46"TP_CPLD1_PR9C";
47"TP_CPLD1_PR9A";
48"TP_CPLD1_PR7D";
49"TP_CPLD1_PR7C";
50"TP_CPLD1_PR7B_PCLKC1_0";
51"TP_CPLD1_PR7A_PCLKT1_0";
52"RST_PLTRST_N";
53"PWRGD_SYS_PWROK";
54"FM_ADR_COMPLETE_DLY";
55"FM_DB1200_PWRGD";
56"TP_CPLD1_PT20D_PROGRAMN";
57"TP_CPLD1_PT24D_DONE";
58"TP_CPLD1_PT24C_INITN";
59"TP_CPLD1_PT24B";
60"TP_CPLD1_PT22D";
61"TP_CPLD1_PT22C";
62"FM_SINT_PRSNT_N";
63"FM_PCH_PWRBTN_N";
64"FM_SLPS4_N";
65"FM_CPU0_OR_CPU1_MCP_PRES";
66"FM_CPU0_CD_PRES";
67"FM_CPU1_CD_PRES";
68"FM_CPU0_AND_CPU1_MCP_PRES";
69"PWRGD_DSW_PWROK";
70"PU_THERMTRIP_FORCE_N";
71"TP_CPLD1_PT19D";
72"TP_CPLD1_PT20B";
73"TP_CPLD1_PT20A";
74"TP_CPLD1_PT17C";
75"TP_CPLD1_PT17B_PCLKC0_1";
76"TP_CPLD1_PT16B";
77"TP_CPLD1_PT13A";
78"TP_CPLD1_PT11B";
79"TP_CPLD1_PT11A";
80"FM_JTAG_PLD_EN_DEBUG";
81"SMB_SENSOR_STBY_LVC3_SDA";
82"FM_SLP_SUS_N";
83"FM_ADR_COMPLETE";
84"FM_BMC_ONCTL_N";
85"RST_PCIE_CPU_DEV0_N";
86"PWRGD_PVTT_CPU0";
87"FM_PCH_PRSNT_N";
88"RST_PCIE_MIDPLANE_N";
89"PU_RST_PERST_BIT1";
90"PWRGD_P1V26_BMC_STBY";
91"FM_CPU1_THERMTRIP_LATCH_LVT3_N";
92"FM_PVCCIN_PVCCSA_CPU0_EN_LVC1";
93"JTAG_PLD_TDO";
94"JTAG_PLD_TDI";
95"FM_CPU1_FIVR_FAULT_LVT3_N";
96"FM_PLD_DEBUG_MODE_N";
97"JTAG_PLD_TCK";
98"JTAG_PLD_TMS";
99"SMB_SENSOR_STBY_LVC3_SCL";
100"FM_PS_EN";
101"SGPIO_BMC_DIN_R";
102"SGPIO_BMC_DIN";
103"FM_FORCE_ADR_N";
104"FM_CTNR_PS_ON";
105"FM_P3V3_CPLD_EN";
106"PWRGD_P12V_MAIN";
107"FM_ADR_SMI_GPIO_N";
%"RES"
"1","(-1425,2675)","0","mstr_discrete","I166";
;
CDS_SEC"1"
SEC_TYPE"0402"
SEC"1"
PACK_TYPE"0402"
CDS_LIB"mstr_discrete"
CDS_LOCATION"R2R6"
ROOM"CPLD"
MATERIAL"CHIP"
WATTAGE"1/16W"
TOLERANCE"5.0%"
VALUE"51"
PART_NUMBER"G21497-048"
LOCATION"R2R6";
"B"
$PN"2"102;
"A"
$PN"1"101;
%"P3V3_STBY"
"1","(-1375,3750)","0","mstr_symbols","I171";
;
SIZE"1B"
CDS_LIB"mstr_symbols"
BODY_TYPE"PLUMBING"
HDL_POWER"P3V3_STBY"
VOLTAGE"3.3V";
"G\NAC"1;
%"RES"
"2","(-1375,3550)","2","mstr_discrete","I172";
;
CDS_SEC"1"
SEC_TYPE"0402"
SEC"1"
CDS_LIB"mstr_discrete"
SIGNAL_MODEL"DEFAULT_RESISTOR_47000OHM_2_1"
BOM_COST"CPLD"
CDS_LOCATION"R2R7"
ROOM"CPLD"
PACK_TYPE"0402"
WATTAGE"1/16W"
MATERIAL"CHIP"
TOLERANCE"1%"
VALUE"4.75K"
PART_NUMBER"G21796-072"
LOCATION"R2R7";
"A"
$PN"1"1;
"B"
$PN"2"103;
%"RES"
"1","(-3200,4325)","0","mstr_discrete","I184";
;
CDS_LIB"mstr_discrete"
BOM_COST"CPLD"
CDS_SEC"1"
$SEC"1"
CDS_LOCATION"R2R4"
ROOM"CPLD"
WATTAGE"1/16W"
TOLERANCE"5%"
MATERIAL"CHIP"
PACK_TYPE"0402"
VALUE"0.0"
PART_NUMBER"G21497-005"
LOCATION"R2R4";
"B"
$PN"2"107;
"A"
$PN"1"3;
%"RES"
"2","(-7225,2675)","0","mstr_discrete","I193";
;
CDS_SEC"1"
CDS_LOCATION"R7D42"
SEC_TYPE"0402"
CDS_LIB"mstr_discrete"
SEC"1"
ROOM"CPLD"
WATTAGE"1/16W"
MATERIAL"CHIP"
PACK_TYPE"0402"
TOLERANCE"1%"
VALUE"4.75K"
PART_NUMBER"G21796-072"
LOCATION"R7D42";
"A"
$PN"1"2;
"B"
$PN"2"4;
%"P3V3_STBY"
"1","(-7225,2900)","0","mstr_symbols","I194";
;
CDS_LIB"mstr_symbols"
SIZE"1B"
BODY_TYPE"PLUMBING"
HDL_POWER"P3V3_STBY"
VOLTAGE"3.3V";
"G\NAC"2;
%"LCMXO2_A"
"5","(-4475,2725)","0","mstr_memory","I59";
;
CDS_SEC"2"
BOM_COST"CPLD"
CDS_LOCATION"U8D7"
CDS_LMAN_SYM_OUTLINE"-550,1700,550,-1700"
CDS_LIB"mstr_memory"
SEC"2"
SEC_TYPE"256BGA"
ROOM"CPLD"
PACK_TYPE"256BGA"
MATERIAL"IC"
PART_NUMBER"H63395-001"
LOCATION"U8D7";
"PR1C"
$PN"C15"55;
"PR1D"
$PN"B16"54;
"PR2A"
$PN"D16"26;
"PR2B"
$PN"E14"7;
"PR2C"
$PN"C16"8;
"PR2D"
$PN"D15"27;
"PR3A"
$PN"E16"28;
"PR3B"
$PN"F15"30;
"PR3C"
$PN"F13"10;
"PR3D"
$PN"G12"21;
"PR4A"
$PN"F14"9;
"PR4B"
$PN"F16"31;
"PR4C"
$PN"F12"29;
"PR5A"
$PN"G15"19;
"PR5B"
$PN"G14"6;
"PR5C"
$PN"G11"18;
"PR5D"
$PN"H12"20;
"PR6A"
$PN"G16"16;
"PR6B"
$PN"H15"14;
"PR6C"
$PN"H13"23;
"PR6D"
$PN"J12"17;
"PR7A_PCLKT1_0"
$PN"H14"51;
"PR7B_PCLKC1_0"
$PN"H16"50;
"PR7C"
$PN"J16"49;
"PR7D"
$PN"J14"48;
"PR9A"
$PN"J15"47;
"PR9B"
$PN"K16"4;
"PR9C"
$PN"H11"46;
"PR9D"
$PN"J13"45;
"PR10A"
$PN"K14"15;
"PR10B"
$PN"K15"13;
"PR10C"
$PN"J11"44;
"PR10D"
$PN"L12"5;
"PR11A"
$PN"L16"24;
"PR11B"
$PN"L14"43;
"PR11C"
$PN"K13"40;
"PR11D"
$PN"K12"22;
"PR12A"
$PN"L15"39;
"PR12B"
$PN"M16"37;
"PR12C"
$PN"K11"38;
"PR12D"
$PN"L13"42;
"PR13A"
$PN"M14"36;
"PR13B"
$PN"M15"41;
"PR13C"
$PN"N15"12;
"PR13D"
$PN"P16"11;
"PR14A"
$PN"N16"25;
"PR14B"
$PN"N14"32;
"PR14C"
$PN"P15"34;
"PR14D"
$PN"R16"35;
"PT9A"
$PN"C4"3;
"PT9B"
$PN"B5"106;
"PT9C"
$PN"B3"104;
"PT10A"
$PN"A4"105;
"PT10B"
$PN"C5"91;
"PT11A"
$PN"A5"79;
"PT11B"
$PN"B6"78;
"PT11C"
$PN"A3"87;
"PT11D"
$PN"B4"86;
"PT12A"
$PN"D6"85;
"PT13A"
$PN"B7"77;
"PT13C"
$PN"E6"95;
"PT13D"
$PN"D7"103;
"PT16A"
$PN"F7"96;
"PT16B"
$PN"E8"76;
"PT16C_TCK"
$PN"A7"97;
"PT16D_TMS"
$PN"B8"98;
"PT17A_PCLKT0_1"
$PN"C8"83;
"PT17B_PCLKC0_1"
$PN"A8"75;
"PT17C"
$PN"D8"74;
"PT17D"
$PN"E9"82;
"PT18A"
$PN"F8"101;
"PT18B"
$PN"D9"88;
"PT18C_SCL_PCLKT0_0"
$PN"A9"99;
"PT18D_SDA_PCLKC0_0"
$PN"C9"81;
"PT19B"
$PN"A10"92;
"PT19C"
$PN"F9"100;
"PT20A"
$PN"D10"73;
"PT20B"
$PN"E10"72;
"PT21A"
$PN"A11"65;
"PT21B"
$PN"C11"66;
"PT21C"
$PN"F10"67;
"PT21D"
$PN"D11"68;
"PT22A"
$PN"B11"69;
"PT22B"
$PN"A12"70;
"PT22C"
$PN"B13"61;
"PT22D"
$PN"A14"60;
"PT23B"
$PN"B12"63;
"PT24A"
$PN"B14"62;
"PT24B"
$PN"A15"59;
"PT24C_INITN"
$PN"A13"58;
"PT24D_DONE"
$PN"C13"57;
"PT19A"
$PN"B9"89;
"PT19D"
$PN"E11"71;
"PT20C_JTAGENB"
$PN"C10"80;
"PT20D_PROGRAMN"
$PN"B10"56;
"PT23A"
$PN"C12"64;
"PR1A"
$PN"D14"53;
"PR1B"
$PN"E15"52;
"PT12B"
$PN"E7"90;
"PT12C_TDO"
$PN"C6"93;
"PT12D_TDI"
$PN"A6"94;
"PT13B"
$PN"C7"84;
"PR4D"
$PN"G13"33;
END.
